(kicad_pcb
	(version 20260206)
	(generator "pcbnew")
	(generator_version "10.0")
	(general
		(thickness 1.6)
		(legacy_teardrops no)
	)
	(paper "A4")
	(title_block
		(title "04192023_DAF0TMB3IC0_F0TG_MB_C_brd_V02_OCP.brd")
		(comment 1 "Grand Teton / footprints 2863-2864 of 8354")
	)
	(layers
		(0 "F.Cu" signal "TOP")
		(4 "In1.Cu" signal "GND")
		(6 "In2.Cu" signal "IN1")
		(8 "In3.Cu" signal "GND1")
		(10 "In4.Cu" signal "IN2")
		(12 "In5.Cu" signal "GND2")
		(14 "In6.Cu" signal "IN3")
		(16 "In7.Cu" signal "GND3")
		(18 "In8.Cu" signal "VCC")
		(20 "In9.Cu" signal "VCC1")
		(22 "In10.Cu" signal "GND4")
		(24 "In11.Cu" signal "IN4")
		(26 "In12.Cu" signal "GND5")
		(28 "In13.Cu" signal "IN5")
		(30 "In14.Cu" signal "GND6")
		(32 "In15.Cu" signal "IN6")
		(34 "In16.Cu" signal "GND7")
		(2 "B.Cu" signal "BOTTOM")
		(9 "F.Adhes" user "F.Adhesive")
		(11 "B.Adhes" user "B.Adhesive")
		(13 "F.Paste" user "Package Geometry/Pastemask Top")
		(15 "B.Paste" user "Package Geometry/Pastemask Bottom")
		(5 "F.SilkS" user "Ref Des/Silkscreen Top")
		(7 "B.SilkS" user "Ref Des/Silkscreen Bottom")
		(1 "F.Mask" user "Board Geometry/Soldermask Top")
		(3 "B.Mask" user "Board Geometry/Soldermask Bottom")
		(17 "Dwgs.User" user "User.Drawings")
		(19 "Cmts.User" user "User.Comments")
		(21 "Eco1.User" user "User.Eco1")
		(23 "Eco2.User" user "User.Eco2")
		(25 "Edge.Cuts" user "Board Geometry/Outline")
		(27 "Margin" user)
		(31 "F.CrtYd" user "Package Geometry/Place Bound Top")
		(29 "B.CrtYd" user "Package Geometry/Place Bound Bottom")
		(35 "F.Fab" user "Ref Des/Assembly Top")
		(33 "B.Fab" user "Ref Des/Assembly Bottom")
	)
	(footprint ""
		(layer "F.Cu")
		(at 112.79886 -31.497778 90)
		(property "Reference" "U6002"
			(at -4.285742 -6.178804 90)
			(unlocked yes)
			(layer "F.SilkS")
			(effects
				(font
					(size 0.7874 0.5842)
					(thickness 0.1524)
				)
				(justify left)
			)
		)
		(property "Value" ""
			(at 0 0 90)
			(layer "F.Fab")
			(effects
				(font
					(size 1.27 1.27)
				)
			)
		)
		(duplicate_pad_numbers_are_jumpers no)
		(fp_line
			(start 4.549902 -4.549902)
			(end 4.549902 -4.014724)
			(stroke
				(width 0.1524)
				(type default)
			)
			(layer "F.SilkS")
		)
		(fp_line
			(start 4.014724 -4.549902)
			(end 4.549902 -4.549902)
			(stroke
				(width 0.1524)
				(type default)
			)
			(layer "F.SilkS")
		)
		(fp_line
			(start -4.549902 -4.549902)
			(end -4.014724 -4.549902)
			(stroke
				(width 0.1524)
				(type default)
			)
			(layer "F.SilkS")
		)
		(fp_line
			(start -4.549902 -4.014724)
			(end -4.549902 -4.549902)
			(stroke
				(width 0.1524)
				(type default)
			)
			(layer "F.SilkS")
		)
		(fp_line
			(start 4.549902 4.014724)
			(end 4.549902 4.549902)
			(stroke
				(width 0.1524)
				(type default)
			)
			(layer "F.SilkS")
		)
		(fp_line
			(start 4.549902 4.549902)
			(end 4.014724 4.549902)
			(stroke
				(width 0.1524)
				(type default)
			)
			(layer "F.SilkS")
		)
		(fp_line
			(start -4.014724 4.549902)
			(end -4.549902 4.549902)
			(stroke
				(width 0.1524)
				(type default)
			)
			(layer "F.SilkS")
		)
		(fp_line
			(start -4.549902 4.549902)
			(end -4.549902 4.014724)
			(stroke
				(width 0.1524)
				(type default)
			)
			(layer "F.SilkS")
		)
		(fp_poly
			(pts
				(xy -5.134102 -4.041902) (xy -4.549902 -4.041902) (xy -4.549902 -4.626102) (xy -5.134102 -4.626102)
			)
			(stroke
				(width 0)
				(type default)
			)
			(fill yes)
			(layer "F.SilkS")
		)
		(fp_line
			(start 4.549902 -4.549902)
			(end 4.549902 4.549902)
			(stroke
				(width 0.1)
				(type default)
			)
			(layer "F.Fab")
		)
		(fp_line
			(start -4.549902 -4.549902)
			(end 4.549902 -4.549902)
			(stroke
				(width 0.1)
				(type default)
			)
			(layer "F.Fab")
		)
		(fp_line
			(start 4.549902 4.549902)
			(end -4.549902 4.549902)
			(stroke
				(width 0.1)
				(type default)
			)
			(layer "F.Fab")
		)
		(fp_line
			(start -4.549902 4.549902)
			(end -4.549902 -4.549902)
			(stroke
				(width 0.1)
				(type default)
			)
			(layer "F.Fab")
		)
		(fp_poly
			(pts
				(xy -5.134102 -4.041902) (xy -4.549902 -4.041902) (xy -4.549902 -4.626102) (xy -5.134102 -4.626102)
			)
			(stroke
				(width 0)
				(type default)
			)
			(fill yes)
			(layer "F.Fab")
		)
		(pad "1" smd circle
			(at -4.400042 -3.750056)
			(size 0 0)
			(layers "F.Cu" "F.Mask" "F.Paste")
			(net "USB_HUB2_TI_USB_DP_DN1_MRP_CFG_STRAP")
		)
		(pad "2" smd circle
			(at -4.400042 -3.24993)
			(size 0 0)
			(layers "F.Cu" "F.Mask" "F.Paste")
			(net "Net_10829")
		)
		(pad "3" smd circle
			(at -4.400042 -2.750058)
			(size 0 0)
			(layers "F.Cu" "F.Mask" "F.Paste")
			(net "Net_10820")
		)
		(pad "4" smd circle
			(at -4.400042 -2.249932)
			(size 0 0)
			(layers "F.Cu" "F.Mask" "F.Paste")
			(net "Net_10823")
		)
		(pad "5" smd circle
			(at -4.400042 -1.75006)
			(size 0 0)
			(layers "F.Cu" "F.Mask" "F.Paste")
			(net "USB_HUB2_TI_VDD_MRP_USB3DN_TXDM1")
		)
		(pad "6" smd circle
			(at -4.400042 -1.249934)
			(size 0 0)
			(layers "F.Cu" "F.Mask" "F.Paste")
			(net "USB_HUB2_TI_USB_SSRXP_DN1_MRP_VDD12")
		)
		(pad "7" smd circle
			(at -4.400042 -0.750062)
			(size 0 0)
			(layers "F.Cu" "F.Mask" "F.Paste")
			(net "Net_10826")
		)
		(pad "8" smd circle
			(at -4.400042 -0.249936)
			(size 0 0)
			(layers "F.Cu" "F.Mask" "F.Paste")
			(net "USB_HUB2_TI_VDD_MRP_USB3DN_RXDM1")
		)
		(pad "9" smd circle
			(at -4.400042 0.249936)
			(size 0 0)
			(layers "F.Cu" "F.Mask" "F.Paste")
			(net "USB2_CPU0_P0_HUB2_R_DP")
		)
		(pad "10" smd circle
			(at -4.400042 0.750062)
			(size 0 0)
			(layers "F.Cu" "F.Mask" "F.Paste")
			(net "USB2_CPU0_P0_HUB2_R_DN")
		)
		(pad "11" smd circle
			(at -4.400042 1.249934)
			(size 0 0)
			(layers "F.Cu" "F.Mask" "F.Paste")
			(net "USB3_CPU0_BMC_HUB2_TX_DP")
		)
		(pad "12" smd circle
			(at -4.400042 1.75006)
			(size 0 0)
			(layers "F.Cu" "F.Mask" "F.Paste")
			(net "USB3_CPU0_BMC_HUB2_TX_DN")
		)
		(pad "13" smd circle
			(at -4.400042 2.249932)
			(size 0 0)
			(layers "F.Cu" "F.Mask" "F.Paste")
			(net "P1V2_CPU0_USB2_DVDD12")
		)
		(pad "14" smd circle
			(at -4.400042 2.750058)
			(size 0 0)
			(layers "F.Cu" "F.Mask" "F.Paste")
			(net "USB3_CPU0_BMC_RX_C2_DP")
		)
		(pad "15" smd circle
			(at -4.400042 3.24993)
			(size 0 0)
			(layers "F.Cu" "F.Mask" "F.Paste")
			(net "USB3_CPU0_BMC_RX_C2_DN")
		)
		(pad "16" smd circle
			(at -4.400042 3.750056)
			(size 0 0)
			(layers "F.Cu" "F.Mask" "F.Paste")
			(net "USB_HUB2_TI_VDD33_MRP_PROG_FUNC7")
		)
		(pad "17" smd circle
			(at -3.750056 4.400042 90)
			(size 0 0)
			(layers "F.Cu" "F.Mask" "F.Paste")
			(net "USB_HUB2_TI_USB_DP_DN3_MRP_VDD12")
		)
		(pad "18" smd circle
			(at -3.24993 4.400042 90)
			(size 0 0)
			(layers "F.Cu" "F.Mask" "F.Paste")
			(net "USB_HUB2_TI_USB_DM_DN3_MRP_VDD33")
		)
		(pad "19" smd circle
			(at -2.750058 4.400042 90)
			(size 0 0)
			(layers "F.Cu" "F.Mask" "F.Paste")
			(net "Net_10819")
		)
		(pad "20" smd circle
			(at -2.249932 4.400042 90)
			(size 0 0)
			(layers "F.Cu" "F.Mask" "F.Paste")
			(net "Net_10822")
		)
		(pad "21" smd circle
			(at -1.75006 4.400042 90)
			(size 0 0)
			(layers "F.Cu" "F.Mask" "F.Paste")
			(net "USB_HUB2_TI_VDD_MRP_USB3DN_TXDP3")
		)
		(pad "22" smd circle
			(at -1.249934 4.400042 90)
			(size 0 0)
			(layers "F.Cu" "F.Mask" "F.Paste")
			(net "Net_10825")
		)
		(pad "23" smd circle
			(at -0.750062 4.400042 90)
			(size 0 0)
			(layers "F.Cu" "F.Mask" "F.Paste")
			(net "USB_HUB2_TI_USB_SSRXM_DN3_MRP_VDD12")
		)
		(pad "24" smd circle
			(at -0.249936 4.400042 90)
			(size 0 0)
			(layers "F.Cu" "F.Mask" "F.Paste")
			(net "Net_10827")
		)
		(pad "25" smd circle
			(at 0.249936 4.400042 90)
			(size 0 0)
			(layers "F.Cu" "F.Mask" "F.Paste")
			(net "Net_10828")
		)
		(pad "26" smd circle
			(at 0.750062 4.400042 90)
			(size 0 0)
			(layers "F.Cu" "F.Mask" "F.Paste")
			(net "Net_10818")
		)
		(pad "27" smd circle
			(at 1.249934 4.400042 90)
			(size 0 0)
			(layers "F.Cu" "F.Mask" "F.Paste")
			(net "Net_10821")
		)
		(pad "28" smd circle
			(at 1.75006 4.400042 90)
			(size 0 0)
			(layers "F.Cu" "F.Mask" "F.Paste")
			(net "USB_HUB2_TI_VDD_MRP_USB3DN_TXDP4")
		)
		(pad "29" smd circle
			(at 2.249932 4.400042 90)
			(size 0 0)
			(layers "F.Cu" "F.Mask" "F.Paste")
			(net "Net_10824")
		)
		(pad "30" smd circle
			(at 2.750058 4.400042 90)
			(size 0 0)
			(layers "F.Cu" "F.Mask" "F.Paste")
			(net "USB_HUB2_TI_USB_SSRXM_DN4_MRP_VDD12")
		)
		(pad "31" smd circle
			(at 3.24993 4.400042 90)
			(size 0 0)
			(layers "F.Cu" "F.Mask" "F.Paste")
			(net "USB_HUB2_TI_VDD_MRP_USB3DN_RXDP4")
		)
		(pad "32" smd circle
			(at 3.750056 4.400042 90)
			(size 0 0)
			(layers "F.Cu" "F.Mask" "F.Paste")
			(net "Net_10830")
		)
		(pad "33" smd circle
			(at 4.400042 3.750056)
			(size 0 0)
			(layers "F.Cu" "F.Mask" "F.Paste")
			(net "USB_HUB2_TI_PWRCTL3_MRP_VDD33")
		)
		(pad "34" smd circle
			(at 4.400042 3.24993)
			(size 0 0)
			(layers "F.Cu" "F.Mask" "F.Paste")
			(net "USB_HUB2_TI_VDD33_MRP_PRT_CTL4_GANGPWR")
		)
		(pad "35" smd circle
			(at 4.400042 2.750058)
			(size 0 0)
			(layers "F.Cu" "F.Mask" "F.Paste")
			(net "USB_HUB2_TI_PWRCTL2_MRP_VDD12")
		)
		(pad "36" smd circle
			(at 4.400042 2.249932)
			(size 0 0)
			(layers "F.Cu" "F.Mask" "F.Paste")
			(net "Net_10831")
		)
		(pad "37" smd circle
			(at 4.400042 1.75006)
			(size 0 0)
			(layers "F.Cu" "F.Mask" "F.Paste")
			(net "SMB_USB_HUB2_TI_SDA_MRP_PRT_CTL2")
		)
		(pad "38" smd circle
			(at 4.400042 1.249934)
			(size 0 0)
			(layers "F.Cu" "F.Mask" "F.Paste")
			(net "SMB_USB_HUB2_TI_SCL_MRP_PRT_CTL1")
		)
		(pad "39" smd circle
			(at 4.400042 0.750062)
			(size 0 0)
			(layers "F.Cu" "F.Mask" "F.Paste")
			(net "USB_HUB2_TI_SMBUSZ_MRP_PROG_FUNC2")
		)
		(pad "40" smd circle
			(at 4.400042 0.249936)
			(size 0 0)
			(layers "F.Cu" "F.Mask" "F.Paste")
			(net "USB_HUB2_TI_FULLPWRMGMTZ_MRP_PROG_FUNC3")
		)
		(pad "41" smd circle
			(at 4.400042 -0.249936)
			(size 0 0)
			(layers "F.Cu" "F.Mask" "F.Paste")
			(net "USB_HUB2_TI_PWRCTL_POL_MRP_VBUS_DET")
		)
		(pad "42" smd circle
			(at 4.400042 -0.750062)
			(size 0 0)
			(layers "F.Cu" "F.Mask" "F.Paste")
			(net "USB_HUB2_TI_GANGED_MRP_I2C_SLV_CFG0")
		)
		(pad "43" smd circle
			(at 4.400042 -1.249934)
			(size 0 0)
			(layers "F.Cu" "F.Mask" "F.Paste")
			(net "USB_HUB2_TI_OVERCUR4_MRP_I2C_SLV_CFG1")
		)
		(pad "44" smd circle
			(at 4.400042 -1.75006)
			(size 0 0)
			(layers "F.Cu" "F.Mask" "F.Paste")
			(net "USB_HUB2_TI_OVERCUR3_MRP_CFG_BC_EN")
		)
		(pad "45" smd circle
			(at 4.400042 -2.249932)
			(size 0 0)
			(layers "F.Cu" "F.Mask" "F.Paste")
			(net "USB_HUB2_TI_HS_SUSPEND_MRP_CFG_NON_REM")
		)
		(pad "46" smd circle
			(at 4.400042 -2.750058)
			(size 0 0)
			(layers "F.Cu" "F.Mask" "F.Paste")
			(net "USB_HUB2_TI_OVERCUR1_MRP_PROG_FUNC4")
		)
		(pad "47" smd circle
			(at 4.400042 -3.24993)
			(size 0 0)
			(layers "F.Cu" "F.Mask" "F.Paste")
			(net "USB_HUB2_TI_OVERCUR2_MRP_PROG_FUNC5")
		)
		(pad "48" smd circle
			(at 4.400042 -3.750056)
			(size 0 0)
			(layers "F.Cu" "F.Mask" "F.Paste")
			(net "USB_HUB2_TI_USB_VBUS_MRP_RESET_N")
		)
		(pad "49" smd circle
			(at 3.750056 -4.400042 90)
			(size 0 0)
			(layers "F.Cu" "F.Mask" "F.Paste")
			(net "USB_HUB2_TI_TEST_MRP_PROG_FUNC6")
		)
		(pad "50" smd circle
			(at 3.24993 -4.400042 90)
			(size 0 0)
			(layers "F.Cu" "F.Mask" "F.Paste")
			(net "USB_HUB2_TI_GRSTZ_MRP_PROG_FUNC1")
		)
		(pad "51" smd circle
			(at 2.750058 -4.400042 90)
			(size 0 0)
			(layers "F.Cu" "F.Mask" "F.Paste")
			(net "P1V2_CPU0_USB2_DVDD12")
		)
		(pad "52" smd circle
			(at 2.249932 -4.400042 90)
			(size 0 0)
			(layers "F.Cu" "F.Mask" "F.Paste")
			(net "P3V3_AUX_CPU0_USB2_AVDD33")
		)
		(pad "53" smd circle
			(at 1.75006 -4.400042 90)
			(size 0 0)
			(layers "F.Cu" "F.Mask" "F.Paste")
			(net "USB2_CPU0_P0_R2_DP")
		)
		(pad "54" smd circle
			(at 1.249934 -4.400042 90)
			(size 0 0)
			(layers "F.Cu" "F.Mask" "F.Paste")
			(net "USB2_CPU0_P0_R2_DN")
		)
		(pad "55" smd circle
			(at 0.750062 -4.400042 90)
			(size 0 0)
			(layers "F.Cu" "F.Mask" "F.Paste")
			(net "USB3_CPU0_BMC_RX_HUB2_DP")
		)
		(pad "56" smd circle
			(at 0.249936 -4.400042 90)
			(size 0 0)
			(layers "F.Cu" "F.Mask" "F.Paste")
			(net "USB3_CPU0_BMC_RX_HUB2_DN")
		)
		(pad "57" smd circle
			(at -0.249936 -4.400042 90)
			(size 0 0)
			(layers "F.Cu" "F.Mask" "F.Paste")
			(net "P1V2_CPU0_USB2_DVDD12")
		)
		(pad "58" smd circle
			(at -0.750062 -4.400042 90)
			(size 0 0)
			(layers "F.Cu" "F.Mask" "F.Paste")
			(net "USB3_CPU0_BMC_TX_C2_DP")
		)
		(pad "59" smd circle
			(at -1.249934 -4.400042 90)
			(size 0 0)
			(layers "F.Cu" "F.Mask" "F.Paste")
			(net "USB3_CPU0_BMC_TX_C2_DN")
		)
		(pad "60" smd circle
			(at -1.75006 -4.400042 90)
			(size 0 0)
			(layers "F.Cu" "F.Mask" "F.Paste")
			(net "USB_HUB2_TI_NC_MRP_ATEST")
		)
		(pad "61" smd circle
			(at -2.249932 -4.400042 90)
			(size 0 0)
			(layers "F.Cu" "F.Mask" "F.Paste")
			(net "XTAL_USB_CPU0_HUB2_XOUT")
		)
		(pad "62" smd circle
			(at -2.750058 -4.400042 90)
			(size 0 0)
			(layers "F.Cu" "F.Mask" "F.Paste")
			(net "XTAL_USB_CPU0_HUB2_XIN")
		)
		(pad "63" smd circle
			(at -3.24993 -4.400042 90)
			(size 0 0)
			(layers "F.Cu" "F.Mask" "F.Paste")
			(net "P3V3_AUX_CPU0_USB2_AVDD33")
		)
		(pad "64" smd circle
			(at -3.750056 -4.400042 90)
			(size 0 0)
			(layers "F.Cu" "F.Mask" "F.Paste")
			(net "USB_HUB2_TI_USB_R1_MRP_RBIAS")
		)
		(pad "TH" smd circle
			(at 0 0 90)
			(size 0 0)
			(layers "F.Cu" "F.Mask" "F.Paste")
			(net "GND")
		)
		(zone
			(layer "F.Cu")
			(hatch none 0.5)
			(connect_pads
				(clearance 0)
			)
			(min_thickness 0.25)
			(keepout
				(tracks not_allowed)
				(vias allowed)
				(pads allowed)
				(copperpour not_allowed)
				(footprints allowed)
			)
			(placement
				(enabled no)
				(sheetname "")
			)
			(fill
				(thermal_gap 0.5)
				(thermal_bridge_width 0.5)
				(island_removal_mode 0)
			)
			(polygon
				(pts
					(xy 116.83746 -27.459178) (xy 112.82426 -27.459178) (xy 112.82426 -28.446984)
					(arc
						(start 115.748816 -28.446984)
						(mid 115.820119 -28.476519)
						(end 115.849654 -28.547822)
					)
					(arc
						(start 115.849654 -34.447734)
						(mid 115.820119 -34.519037)
						(end 115.748816 -34.548572)
					)
					(arc
						(start 109.848904 -34.548572)
						(mid 109.777601 -34.519037)
						(end 109.748066 -34.447734)
					)
					(arc
						(start 109.748066 -28.547822)
						(mid 109.777601 -28.476519)
						(end 109.848904 -28.446984)
					)
					(xy 112.77346 -28.446984) (xy 112.79886 -28.446984) (xy 112.79886 -27.459178) (xy 112.77346 -27.459178)
					(xy 108.76026 -27.459178) (xy 108.76026 -35.536378) (xy 116.83746 -35.536378)
				)
			)
		)
	)
	(footprint ""
		(layer "F.Cu")
		(at 406.475946 -136.231376 180)
		(property "Reference" "R2346"
			(at 0 0 180)
			(layer "F.SilkS")
			(hide yes)
			(effects
				(font
					(size 1.27 1.27)
				)
			)
		)
		(property "Value" ""
			(at 0 0 180)
			(layer "F.Fab")
			(effects
				(font
					(size 1.27 1.27)
				)
			)
		)
		(duplicate_pad_numbers_are_jumpers no)
		(fp_line
			(start 0.7874 0.4064)
			(end -0.7874 0.4064)
			(stroke
				(width 0.1524)
				(type default)
			)
			(layer "F.SilkS")
		)
		(fp_line
			(start 0.7874 -0.4064)
			(end 0.7874 0.4064)
			(stroke
				(width 0.1524)
				(type default)
			)
			(layer "F.SilkS")
		)
		(fp_line
			(start -0.7874 0.4064)
			(end -0.7874 -0.4064)
			(stroke
				(width 0.1524)
				(type default)
			)
			(layer "F.SilkS")
		)
		(fp_line
			(start -0.7874 -0.4064)
			(end 0.7874 -0.4064)
			(stroke
				(width 0.1524)
				(type default)
			)
			(layer "F.SilkS")
		)
		(fp_line
			(start 0.67945 0.3048)
			(end 0.120396 0.3048)
			(stroke
				(width 0.1)
				(type default)
			)
			(layer "F.Fab")
		)
		(fp_line
			(start 0.67945 -0.3048)
			(end 0.67945 0.3048)
			(stroke
				(width 0.1)
				(type default)
			)
			(layer "F.Fab")
		)
		(fp_line
			(start 0.12065 -0.2794)
			(end 0.12065 -0.3048)
			(stroke
				(width 0.1)
				(type default)
			)
			(layer "F.Fab")
		)
		(fp_line
			(start 0.12065 -0.3048)
			(end 0.67945 -0.3048)
			(stroke
				(width 0.1)
				(type default)
			)
			(layer "F.Fab")
		)
		(fp_line
			(start 0.120396 0.3048)
			(end 0.120396 0.2794)
			(stroke
				(width 0.1)
				(type default)
			)
			(layer "F.Fab")
		)
		(fp_line
			(start 0.120396 0.2794)
			(end -0.12065 0.2794)
			(stroke
				(width 0.1)
				(type default)
			)
			(layer "F.Fab")
		)
		(fp_line
			(start -0.12065 0.3048)
			(end -0.67945 0.3048)
			(stroke
				(width 0.1)
				(type default)
			)
			(layer "F.Fab")
		)
		(fp_line
			(start -0.12065 0.2794)
			(end -0.12065 0.3048)
			(stroke
				(width 0.1)
				(type default)
			)
			(layer "F.Fab")
		)
		(fp_line
			(start -0.12065 -0.2794)
			(end 0.12065 -0.2794)
			(stroke
				(width 0.1)
				(type default)
			)
			(layer "F.Fab")
		)
		(fp_line
			(start -0.12065 -0.305054)
			(end -0.12065 -0.2794)
			(stroke
				(width 0.1)
				(type default)
			)
			(layer "F.Fab")
		)
		(fp_line
			(start -0.67945 0.3048)
			(end -0.67945 -0.305054)
			(stroke
				(width 0.1)
				(type default)
			)
			(layer "F.Fab")
		)
		(fp_line
			(start -0.67945 -0.305054)
			(end -0.12065 -0.305054)
			(stroke
				(width 0.1)
				(type default)
			)
			(layer "F.Fab")
		)
		(pad "1" smd circle
			(at -0.40005 0 180)
			(size 0 0)
			(layers "F.Cu" "F.Mask" "F.Paste")
			(net "P3V3_AUX")
		)
		(pad "2" smd circle
			(at 0.40005 0 180)
			(size 0 0)
			(layers "F.Cu" "F.Mask" "F.Paste")
			(net "PWRGD_P5V_AUX_R2")
		)
	)
)
